(kicad_pcb
	(version 20260206)
	(generator "pcbnew")
	(generator_version "10.0")
	(general
		(thickness 1.6)
		(legacy_teardrops no)
	)
	(paper "A4")
	(title_block
		(title "Bryce Canyon_IOM_M2_16342-2_OCP.brd")
		(comment 1 "Bryce Canyon / footprints 917-924 of 1146")
	)
	(layers
		(0 "F.Cu" signal "TOP")
		(4 "In1.Cu" signal "L2GND")
		(6 "In2.Cu" signal "L3")
		(8 "In3.Cu" signal "L4VCC")
		(10 "In4.Cu" signal "L5VCC")
		(12 "In5.Cu" signal "L6")
		(14 "In6.Cu" signal "L7GND")
		(2 "B.Cu" signal "BOTTOM")
		(9 "F.Adhes" user "F.Adhesive")
		(11 "B.Adhes" user "B.Adhesive")
		(13 "F.Paste" user "Package Geometry/Pastemask Top")
		(15 "B.Paste" user "Package Geometry/Pastemask Bottom")
		(5 "F.SilkS" user "Ref Des/Silkscreen Top")
		(7 "B.SilkS" user "Ref Des/Silkscreen Bottom")
		(1 "F.Mask" user "Board Geometry/Soldermask Top")
		(3 "B.Mask" user "Board Geometry/Soldermask Bottom")
		(17 "Dwgs.User" user "User.Drawings")
		(19 "Cmts.User" user "User.Comments")
		(21 "Eco1.User" user "User.Eco1")
		(23 "Eco2.User" user "User.Eco2")
		(25 "Edge.Cuts" user "Board Geometry/Outline")
		(27 "Margin" user)
		(31 "F.CrtYd" user "Package Geometry/Place Bound Top")
		(29 "B.CrtYd" user "Package Geometry/Place Bound Bottom")
		(35 "F.Fab" user "Ref Des/Assembly Top")
		(33 "B.Fab" user "Ref Des/Assembly Bottom")
	)
	(footprint ""
		(layer "B.Cu")
		(at 50.807874 -135.761476)
		(property "Reference" "R607"
			(at 0 0 0)
			(layer "B.SilkS")
			(hide yes)
			(effects
				(font
					(size 1.27 1.27)
				)
				(justify mirror)
			)
		)
		(property "Value" "0R2J-2-GP"
			(at -0.064008 -3.993896 0)
			(unlocked yes)
			(layer "B.Fab")
			(hide yes)
			(effects
				(font
					(size 1.016 1.016)
					(thickness 0.1524)
				)
				(justify mirror)
			)
		)
		(property "Device Type" "R402H16"
			(at -0.064008 -5.517896 0)
			(unlocked yes)
			(layer "B.Fab")
			(hide yes)
			(effects
				(font
					(size 1.016 1.016)
					(thickness 0.1524)
				)
				(justify mirror)
			)
		)
		(duplicate_pad_numbers_are_jumpers no)
		(fp_line
			(start -0.508 -0.9398)
			(end 0.508 -0.9398)
			(stroke
				(width 0.1524)
				(type default)
			)
			(layer "B.SilkS")
		)
		(fp_line
			(start 0.508 -0.9398)
			(end 0.508 0.9398)
			(stroke
				(width 0.1524)
				(type default)
			)
			(layer "B.SilkS")
		)
		(fp_rect
			(start 0.508 0.9398)
			(end -0.508 -0.9398)
			(stroke
				(width 0)
				(type default)
			)
			(fill no)
			(layer "B.CrtYd")
		)
		(fp_rect
			(start 0.508 0.9398)
			(end -0.508 -0.9398)
			(stroke
				(width 0)
				(type default)
			)
			(fill no)
			(layer "B.Fab")
		)
		(pad "1" smd custom
			(at 0 -0.4445 180)
			(size 0.1397 0.1397)
			(layers "B.Cu" "B.Mask" "B.Paste")
			(net "SYS_RESET_N_OUT_R")
			(options
				(clearance outline)
				(anchor circle)
			)
			(primitives
				(gr_poly
					(pts
						(arc
							(start -0.1778 0.2794)
							(mid -0.249642 0.249642)
							(end -0.2794 0.1778)
						)
						(arc
							(start -0.2794 -0.1778)
							(mid -0.249642 -0.249642)
							(end -0.1778 -0.2794)
						)
						(arc
							(start 0.1778 -0.2794)
							(mid 0.249642 -0.249642)
							(end 0.2794 -0.1778)
						)
						(arc
							(start 0.2794 0.1778)
							(mid 0.249642 0.249642)
							(end 0.1778 0.2794)
						)
					)
					(width 0)
					(fill yes)
				)
			)
		)
		(pad "2" smd custom
			(at 0 0.4445 180)
			(size 0.1397 0.1397)
			(layers "B.Cu" "B.Mask" "B.Paste")
			(net "SYS_RESET_N_OUT")
			(options
				(clearance outline)
				(anchor circle)
			)
			(primitives
				(gr_poly
					(pts
						(arc
							(start -0.1778 0.2794)
							(mid -0.249642 0.249642)
							(end -0.2794 0.1778)
						)
						(arc
							(start -0.2794 -0.1778)
							(mid -0.249642 -0.249642)
							(end -0.1778 -0.2794)
						)
						(arc
							(start 0.1778 -0.2794)
							(mid 0.249642 -0.249642)
							(end 0.2794 -0.1778)
						)
						(arc
							(start 0.2794 0.1778)
							(mid 0.249642 0.249642)
							(end 0.1778 0.2794)
						)
					)
					(width 0)
					(fill yes)
				)
			)
		)
	)
	(footprint ""
		(layer "B.Cu")
		(at 148.957538 -14.987778)
		(property "Reference" "C212"
			(at 0 0 0)
			(layer "B.SilkS")
			(hide yes)
			(effects
				(font
					(size 1.27 1.27)
				)
				(justify mirror)
			)
		)
		(property "Value" "SC1KP50V2KX-1GP"
			(at -1.1811 -2.7051 0)
			(unlocked yes)
			(layer "B.Fab")
			(hide yes)
			(effects
				(font
					(size 1.016 1.016)
					(thickness 0.1524)
				)
				(justify mirror)
			)
		)
		(property "Device Type" "C402H22"
			(at -1.1811 -4.2291 0)
			(unlocked yes)
			(layer "B.Fab")
			(hide yes)
			(effects
				(font
					(size 1.016 1.016)
					(thickness 0.1524)
				)
				(justify mirror)
			)
		)
		(duplicate_pad_numbers_are_jumpers no)
		(fp_rect
			(start 0.4318 0.9525)
			(end -0.4318 -0.9525)
			(stroke
				(width 0)
				(type default)
			)
			(fill no)
			(layer "B.CrtYd")
		)
		(fp_rect
			(start 0.4318 0.9525)
			(end -0.4318 -0.9525)
			(stroke
				(width 0)
				(type default)
			)
			(fill no)
			(layer "B.Fab")
		)
		(pad "1" smd custom
			(at 0 -0.4445 180)
			(size 0.1524 0.1524)
			(layers "B.Cu" "B.Mask" "B.Paste")
			(net "P1V8_STBY_VFB_R")
			(options
				(clearance outline)
				(anchor circle)
			)
			(primitives
				(gr_poly
					(pts
						(arc
							(start 0.3048 0.2032)
							(mid 0.275042 0.275042)
							(end 0.2032 0.3048)
						)
						(arc
							(start -0.2032 0.3048)
							(mid -0.275042 0.275042)
							(end -0.3048 0.2032)
						)
						(arc
							(start -0.3048 -0.2032)
							(mid -0.275042 -0.275042)
							(end -0.2032 -0.3048)
						)
						(arc
							(start 0.2032 -0.3048)
							(mid 0.275042 -0.275042)
							(end 0.3048 -0.2032)
						)
					)
					(width 0)
					(fill yes)
				)
			)
		)
		(pad "2" smd custom
			(at 0 0.4445 180)
			(size 0.1524 0.1524)
			(layers "B.Cu" "B.Mask" "B.Paste")
			(net "P1V8_STBY_VFB")
			(options
				(clearance outline)
				(anchor circle)
			)
			(primitives
				(gr_poly
					(pts
						(arc
							(start 0.3048 0.2032)
							(mid 0.275042 0.275042)
							(end 0.2032 0.3048)
						)
						(arc
							(start -0.2032 0.3048)
							(mid -0.275042 0.275042)
							(end -0.3048 0.2032)
						)
						(arc
							(start -0.3048 -0.2032)
							(mid -0.275042 -0.275042)
							(end -0.2032 -0.3048)
						)
						(arc
							(start 0.2032 -0.3048)
							(mid 0.275042 -0.275042)
							(end 0.3048 -0.2032)
						)
					)
					(width 0)
					(fill yes)
				)
			)
		)
	)
	(footprint ""
		(layer "B.Cu")
		(at 42.987468 -153.189178)
		(property "Reference" "TP63"
			(at 0 0 0)
			(layer "B.SilkS")
			(hide yes)
			(effects
				(font
					(size 1.27 1.27)
				)
				(justify mirror)
			)
		)
		(property "Value" "TPAD28-2-GP"
			(at 0.0127 -1.6637 0)
			(unlocked yes)
			(layer "B.Fab")
			(hide yes)
			(effects
				(font
					(size 1.016 1.016)
					(thickness 0.1524)
				)
				(justify mirror)
			)
		)
		(property "Device Type" "TPAD28"
			(at 0.0127 -3.1877 0)
			(unlocked yes)
			(layer "B.Fab")
			(hide yes)
			(effects
				(font
					(size 1.016 1.016)
					(thickness 0.1524)
				)
				(justify mirror)
			)
		)
		(duplicate_pad_numbers_are_jumpers no)
		(fp_poly
			(pts
				(arc
					(start 0.3556 0)
					(mid -0.3556 0)
					(end 0.3556 0)
				)
			)
			(stroke
				(width 0)
				(type default)
			)
			(fill no)
			(layer "B.CrtYd")
		)
		(fp_poly
			(pts
				(arc
					(start 0.6096 0)
					(mid -0.6096 0)
					(end 0.6096 0)
				)
			)
			(stroke
				(width 0)
				(type default)
			)
			(fill no)
			(layer "B.Fab")
		)
		(pad "1" smd circle
			(at 0 0 180)
			(size 0.7112 0.7112)
			(layers "B.Cu" "B.Mask" "B.Paste")
			(net "TP_BMC_GPION3")
		)
	)
	(footprint ""
		(layer "B.Cu")
		(at 61.83122 -145.042128 90)
		(property "Reference" "R165"
			(at 0 0 90)
			(layer "B.SilkS")
			(hide yes)
			(effects
				(font
					(size 1.27 1.27)
				)
				(justify mirror)
			)
		)
		(property "Value" "0R2J-2-GP"
			(at -0.064008 -3.993896 90)
			(unlocked yes)
			(layer "B.Fab")
			(hide yes)
			(effects
				(font
					(size 1.016 1.016)
					(thickness 0.1524)
				)
				(justify mirror)
			)
		)
		(property "Device Type" "R402H16"
			(at -0.064008 -5.517896 90)
			(unlocked yes)
			(layer "B.Fab")
			(hide yes)
			(effects
				(font
					(size 1.016 1.016)
					(thickness 0.1524)
				)
				(justify mirror)
			)
		)
		(duplicate_pad_numbers_are_jumpers no)
		(fp_line
			(start 0.508 -0.9398)
			(end 0.508 0.9398)
			(stroke
				(width 0.1524)
				(type default)
			)
			(layer "B.SilkS")
		)
		(fp_line
			(start -0.508 -0.9398)
			(end 0.508 -0.9398)
			(stroke
				(width 0.1524)
				(type default)
			)
			(layer "B.SilkS")
		)
		(fp_rect
			(start 0.508 0.9398)
			(end -0.508 -0.9398)
			(stroke
				(width 0)
				(type default)
			)
			(fill no)
			(layer "B.CrtYd")
		)
		(fp_rect
			(start 0.508 0.9398)
			(end -0.508 -0.9398)
			(stroke
				(width 0)
				(type default)
			)
			(fill no)
			(layer "B.Fab")
		)
		(pad "1" smd custom
			(at 0 -0.4445 270)
			(size 0.1397 0.1397)
			(layers "B.Cu" "B.Mask" "B.Paste")
			(net "BMC_SMB13_DAT")
			(options
				(clearance outline)
				(anchor circle)
			)
			(primitives
				(gr_poly
					(pts
						(arc
							(start -0.1778 0.2794)
							(mid -0.249642 0.249642)
							(end -0.2794 0.1778)
						)
						(arc
							(start -0.2794 -0.1778)
							(mid -0.249642 -0.249642)
							(end -0.1778 -0.2794)
						)
						(arc
							(start 0.1778 -0.2794)
							(mid 0.249642 -0.249642)
							(end 0.2794 -0.1778)
						)
						(arc
							(start 0.2794 0.1778)
							(mid 0.249642 0.249642)
							(end 0.1778 0.2794)
						)
					)
					(width 0)
					(fill yes)
				)
			)
		)
		(pad "2" smd custom
			(at 0 0.4445 270)
			(size 0.1397 0.1397)
			(layers "B.Cu" "B.Mask" "B.Paste")
			(net "I2C_MEZZ_FRU_SENSOR_SDA")
			(options
				(clearance outline)
				(anchor circle)
			)
			(primitives
				(gr_poly
					(pts
						(arc
							(start -0.1778 0.2794)
							(mid -0.249642 0.249642)
							(end -0.2794 0.1778)
						)
						(arc
							(start -0.2794 -0.1778)
							(mid -0.249642 -0.249642)
							(end -0.1778 -0.2794)
						)
						(arc
							(start 0.1778 -0.2794)
							(mid 0.249642 -0.249642)
							(end 0.2794 -0.1778)
						)
						(arc
							(start 0.2794 0.1778)
							(mid 0.249642 0.249642)
							(end 0.1778 0.2794)
						)
					)
					(width 0)
					(fill yes)
				)
			)
		)
	)
	(footprint ""
		(layer "B.Cu")
		(at 61.6204 -146.5072)
		(property "Reference" "R163"
			(at 0 0 0)
			(layer "B.SilkS")
			(hide yes)
			(effects
				(font
					(size 1.27 1.27)
				)
				(justify mirror)
			)
		)
		(property "Value" "0R2J-2-GP"
			(at -0.064008 -3.993896 0)
			(unlocked yes)
			(layer "B.Fab")
			(hide yes)
			(effects
				(font
					(size 1.016 1.016)
					(thickness 0.1524)
				)
				(justify mirror)
			)
		)
		(property "Device Type" "R402H16"
			(at -0.064008 -5.517896 0)
			(unlocked yes)
			(layer "B.Fab")
			(hide yes)
			(effects
				(font
					(size 1.016 1.016)
					(thickness 0.1524)
				)
				(justify mirror)
			)
		)
		(duplicate_pad_numbers_are_jumpers no)
		(fp_line
			(start -0.508 -0.9398)
			(end 0.508 -0.9398)
			(stroke
				(width 0.1524)
				(type default)
			)
			(layer "B.SilkS")
		)
		(fp_line
			(start 0.508 -0.9398)
			(end 0.508 0.9398)
			(stroke
				(width 0.1524)
				(type default)
			)
			(layer "B.SilkS")
		)
		(fp_rect
			(start 0.508 0.9398)
			(end -0.508 -0.9398)
			(stroke
				(width 0)
				(type default)
			)
			(fill no)
			(layer "B.CrtYd")
		)
		(fp_rect
			(start 0.508 0.9398)
			(end -0.508 -0.9398)
			(stroke
				(width 0)
				(type default)
			)
			(fill no)
			(layer "B.Fab")
		)
		(pad "1" smd custom
			(at 0 -0.4445 180)
			(size 0.1397 0.1397)
			(layers "B.Cu" "B.Mask" "B.Paste")
			(net "BMC_SMB13_CLK")
			(options
				(clearance outline)
				(anchor circle)
			)
			(primitives
				(gr_poly
					(pts
						(arc
							(start -0.1778 0.2794)
							(mid -0.249642 0.249642)
							(end -0.2794 0.1778)
						)
						(arc
							(start -0.2794 -0.1778)
							(mid -0.249642 -0.249642)
							(end -0.1778 -0.2794)
						)
						(arc
							(start 0.1778 -0.2794)
							(mid 0.249642 -0.249642)
							(end 0.2794 -0.1778)
						)
						(arc
							(start 0.2794 0.1778)
							(mid 0.249642 0.249642)
							(end 0.1778 0.2794)
						)
					)
					(width 0)
					(fill yes)
				)
			)
		)
		(pad "2" smd custom
			(at 0 0.4445 180)
			(size 0.1397 0.1397)
			(layers "B.Cu" "B.Mask" "B.Paste")
			(net "I2C_MEZZ_FRU_SENSOR_SCL")
			(options
				(clearance outline)
				(anchor circle)
			)
			(primitives
				(gr_poly
					(pts
						(arc
							(start -0.1778 0.2794)
							(mid -0.249642 0.249642)
							(end -0.2794 0.1778)
						)
						(arc
							(start -0.2794 -0.1778)
							(mid -0.249642 -0.249642)
							(end -0.1778 -0.2794)
						)
						(arc
							(start 0.1778 -0.2794)
							(mid 0.249642 -0.249642)
							(end 0.2794 -0.1778)
						)
						(arc
							(start 0.2794 0.1778)
							(mid 0.249642 0.249642)
							(end 0.1778 0.2794)
						)
					)
					(width 0)
					(fill yes)
				)
			)
		)
	)
	(footprint ""
		(layer "B.Cu")
		(at 224.989644 -76.13523 90)
		(property "Reference" "C640"
			(at 0 0 90)
			(layer "B.SilkS")
			(hide yes)
			(effects
				(font
					(size 1.27 1.27)
				)
				(justify mirror)
			)
		)
		(property "Value" "SC10U6D3V5KX-4GP"
			(at 0.0762 -6.1214 90)
			(unlocked yes)
			(layer "B.Fab")
			(hide yes)
			(effects
				(font
					(size 1.016 1.016)
					(thickness 0.1524)
				)
				(justify mirror)
			)
		)
		(property "Device Type" "C805H58"
			(at 0.0762 -8.1534 90)
			(unlocked yes)
			(layer "B.Fab")
			(hide yes)
			(effects
				(font
					(size 1.016 1.016)
					(thickness 0.1524)
				)
				(justify mirror)
			)
		)
		(duplicate_pad_numbers_are_jumpers no)
		(fp_line
			(start -0.635 0)
			(end 0.635 0)
			(stroke
				(width 0.508)
				(type default)
			)
			(layer "B.SilkS")
		)
		(fp_rect
			(start 0.9652 1.778)
			(end -0.9652 -1.778)
			(stroke
				(width 0)
				(type default)
			)
			(fill no)
			(layer "B.CrtYd")
		)
		(fp_poly
			(pts
				(xy 0.9652 -1.778) (xy -0.9652 -1.778) (xy -0.9652 1.778) (xy 0.9652 1.778)
			)
			(stroke
				(width 0)
				(type default)
			)
			(fill no)
			(layer "B.Fab")
		)
		(pad "1" smd rect
			(at 0 -0.9652 270)
			(size 1.397 1.143)
			(layers "B.Cu" "B.Mask" "B.Paste")
			(net "P3V3_M2")
		)
		(pad "2" smd rect
			(at 0 0.9652 270)
			(size 1.397 1.143)
			(layers "B.Cu" "B.Mask" "B.Paste")
			(net "GND")
		)
	)
	(footprint ""
		(layer "B.Cu")
		(at 58.392568 -158.191708 -90)
		(property "Reference" "R394"
			(at 0 0 90)
			(layer "B.SilkS")
			(hide yes)
			(effects
				(font
					(size 1.27 1.27)
				)
				(justify mirror)
			)
		)
		(property "Value" "4K7R2F-GP"
			(at -0.064008 -3.993896 270)
			(unlocked yes)
			(layer "B.Fab")
			(hide yes)
			(effects
				(font
					(size 1.016 1.016)
					(thickness 0.1524)
				)
				(justify mirror)
			)
		)
		(property "Device Type" "R402H16"
			(at -0.064008 -5.517896 270)
			(unlocked yes)
			(layer "B.Fab")
			(hide yes)
			(effects
				(font
					(size 1.016 1.016)
					(thickness 0.1524)
				)
				(justify mirror)
			)
		)
		(duplicate_pad_numbers_are_jumpers no)
		(fp_line
			(start -0.508 -0.9398)
			(end 0.508 -0.9398)
			(stroke
				(width 0.1524)
				(type default)
			)
			(layer "B.SilkS")
		)
		(fp_line
			(start 0.508 -0.9398)
			(end 0.508 0.9398)
			(stroke
				(width 0.1524)
				(type default)
			)
			(layer "B.SilkS")
		)
		(fp_rect
			(start 0.508 0.9398)
			(end -0.508 -0.9398)
			(stroke
				(width 0)
				(type default)
			)
			(fill no)
			(layer "B.CrtYd")
		)
		(fp_rect
			(start 0.508 0.9398)
			(end -0.508 -0.9398)
			(stroke
				(width 0)
				(type default)
			)
			(fill no)
			(layer "B.Fab")
		)
		(pad "1" smd custom
			(at 0 -0.4445 90)
			(size 0.1397 0.1397)
			(layers "B.Cu" "B.Mask" "B.Paste")
			(net "P3V3_STBY")
			(options
				(clearance outline)
				(anchor circle)
			)
			(primitives
				(gr_poly
					(pts
						(arc
							(start -0.1778 0.2794)
							(mid -0.249642 0.249642)
							(end -0.2794 0.1778)
						)
						(arc
							(start -0.2794 -0.1778)
							(mid -0.249642 -0.249642)
							(end -0.1778 -0.2794)
						)
						(arc
							(start 0.1778 -0.2794)
							(mid 0.249642 -0.249642)
							(end 0.2794 -0.1778)
						)
						(arc
							(start 0.2794 0.1778)
							(mid 0.249642 0.249642)
							(end 0.1778 0.2794)
						)
					)
					(width 0)
					(fill yes)
				)
			)
		)
		(pad "2" smd custom
			(at 0 0.4445 90)
			(size 0.1397 0.1397)
			(layers "B.Cu" "B.Mask" "B.Paste")
			(net "MAC2_TXD3")
			(options
				(clearance outline)
				(anchor circle)
			)
			(primitives
				(gr_poly
					(pts
						(arc
							(start -0.1778 0.2794)
							(mid -0.249642 0.249642)
							(end -0.2794 0.1778)
						)
						(arc
							(start -0.2794 -0.1778)
							(mid -0.249642 -0.249642)
							(end -0.1778 -0.2794)
						)
						(arc
							(start 0.1778 -0.2794)
							(mid 0.249642 -0.249642)
							(end 0.2794 -0.1778)
						)
						(arc
							(start 0.2794 0.1778)
							(mid 0.249642 0.249642)
							(end 0.1778 0.2794)
						)
					)
					(width 0)
					(fill yes)
				)
			)
		)
	)
	(footprint ""
		(layer "B.Cu")
		(at 177.8 -112.2934 -90)
		(property "Reference" "R527"
			(at 0 0 90)
			(layer "B.SilkS")
			(hide yes)
			(effects
				(font
					(size 1.27 1.27)
				)
				(justify mirror)
			)
		)
		(property "Value" "0R2J-2-GP"
			(at -0.064008 -3.993896 270)
			(unlocked yes)
			(layer "B.Fab")
			(hide yes)
			(effects
				(font
					(size 1.016 1.016)
					(thickness 0.1524)
				)
				(justify mirror)
			)
		)
		(property "Device Type" "R402H16"
			(at -0.064008 -5.517896 270)
			(unlocked yes)
			(layer "B.Fab")
			(hide yes)
			(effects
				(font
					(size 1.016 1.016)
					(thickness 0.1524)
				)
				(justify mirror)
			)
		)
		(duplicate_pad_numbers_are_jumpers no)
		(fp_line
			(start -0.508 -0.9398)
			(end 0.508 -0.9398)
			(stroke
				(width 0.1524)
				(type default)
			)
			(layer "B.SilkS")
		)
		(fp_line
			(start 0.508 -0.9398)
			(end 0.508 0.9398)
			(stroke
				(width 0.1524)
				(type default)
			)
			(layer "B.SilkS")
		)
		(fp_rect
			(start 0.508 0.9398)
			(end -0.508 -0.9398)
			(stroke
				(width 0)
				(type default)
			)
			(fill no)
			(layer "B.CrtYd")
		)
		(fp_rect
			(start 0.508 0.9398)
			(end -0.508 -0.9398)
			(stroke
				(width 0)
				(type default)
			)
			(fill no)
			(layer "B.Fab")
		)
		(pad "1" smd custom
			(at 0 -0.4445 90)
			(size 0.1397 0.1397)
			(layers "B.Cu" "B.Mask" "B.Paste")
			(net "IOM_FULL_PGOOD")
			(options
				(clearance outline)
				(anchor circle)
			)
			(primitives
				(gr_poly
					(pts
						(arc
							(start -0.1778 0.2794)
							(mid -0.249642 0.249642)
							(end -0.2794 0.1778)
						)
						(arc
							(start -0.2794 -0.1778)
							(mid -0.249642 -0.249642)
							(end -0.1778 -0.2794)
						)
						(arc
							(start 0.1778 -0.2794)
							(mid 0.249642 -0.249642)
							(end 0.2794 -0.1778)
						)
						(arc
							(start 0.2794 0.1778)
							(mid 0.249642 0.249642)
							(end 0.1778 0.2794)
						)
					)
					(width 0)
					(fill yes)
				)
			)
		)
		(pad "2" smd custom
			(at 0 0.4445 90)
			(size 0.1397 0.1397)
			(layers "B.Cu" "B.Mask" "B.Paste")
			(net "U83_VREF2")
			(options
				(clearance outline)
				(anchor circle)
			)
			(primitives
				(gr_poly
					(pts
						(arc
							(start -0.1778 0.2794)
							(mid -0.249642 0.249642)
							(end -0.2794 0.1778)
						)
						(arc
							(start -0.2794 -0.1778)
							(mid -0.249642 -0.249642)
							(end -0.1778 -0.2794)
						)
						(arc
							(start 0.1778 -0.2794)
							(mid 0.249642 -0.249642)
							(end 0.2794 -0.1778)
						)
						(arc
							(start 0.2794 0.1778)
							(mid 0.249642 0.249642)
							(end 0.1778 0.2794)
						)
					)
					(width 0)
					(fill yes)
				)
			)
		)
	)
)
